(kicad_pcb
	(version 20211014)
	(generator pcbnew)
	(general
    (thickness 1.6)
  )
	(paper "A4")
	(title_block
    (title "SA800U (Snapdragon 845) Baseboard")
    (date "2023-10-19")
    (rev "1.0.3")
    (company "Antmicro Ltd.")
    (comment 1 "www.antmicro.com")
		(comment 9 "footprints 211-213 of 589")
	)
	(layers
    (0 "F.Cu" signal)
    (1 "In1.Cu" power)
    (2 "In2.Cu" signal)
    (3 "In3.Cu" signal)
    (4 "In4.Cu" power)
    (31 "B.Cu" signal)
    (32 "B.Adhes" user "B.Adhesive")
    (33 "F.Adhes" user "F.Adhesive")
    (34 "B.Paste" user)
    (35 "F.Paste" user)
    (36 "B.SilkS" user "B.Silkscreen")
    (37 "F.SilkS" user "F.Silkscreen")
    (38 "B.Mask" user)
    (39 "F.Mask" user)
    (40 "Dwgs.User" user "User.Drawings")
    (41 "Cmts.User" user "User.Comments")
    (42 "Eco1.User" user "User.Eco1")
    (43 "Eco2.User" user "User.Eco2")
    (44 "Edge.Cuts" user)
    (45 "Margin" user)
    (46 "B.CrtYd" user "B.Courtyard")
    (47 "F.CrtYd" user "F.Courtyard")
    (48 "B.Fab" user)
    (49 "F.Fab" user)
  )
	(footprint "sa800u-baseboard-hw-footprints:Nexperia_DFN-10_2.5x1mm_P0.5mm" (layer "F.Cu")
    (tedit 6215DC23)
    (at 142.2 139.55)
    (property "Author" "Antmicro")
    (property "License" "Apache-2.0")
    (property "MPN" "PUSB3F96X")
    (property "Manufacturer" "Nexperia")
    (property "Sheetfile" "hdmi-converter.kicad_sch")
    (property "Sheetname" "HDMI converter")
    (attr smd)
    (fp_text reference "D3" (at -1.53 -0.87) (layer "F.SilkS")
      (effects (font (size 0.7 0.7) (thickness 0.15)) (justify left bottom))
    )
    (fp_text value "PUSB3F96X_PASS" (at -0.016 1.705) (layer "F.Fab")
      (effects (font (size 0.7 0.7) (thickness 0.15)) (justify left bottom))
    )
    (fp_text user "License: Apache-2.0" (at -1.367 6.105) (layer "F.Fab") hide
      (effects (font (size 0.7 0.7) (thickness 0.15)) (justify left bottom))
    )
    (fp_text user "${REFERENCE}" (at -1.367 3.704) (layer "F.Fab") hide
      (effects (font (size 0.7 0.7) (thickness 0.15)) (justify left bottom))
    )
    (fp_text user "Author: Antmicro" (at -1.367 4.905) (layer "F.Fab") hide
      (effects (font (size 0.7 0.7) (thickness 0.15)) (justify left bottom))
    )
    (fp_line (start -1.266 -0.396) (end -1.266 0.405) (layer "F.SilkS") (width 0.15))
    (fp_line (start 1.233 0.405) (end 1.233 -0.396) (layer "F.SilkS") (width 0.15))
    (fp_circle (center -1.317 0.704) (end -1.266 0.704) (layer "F.SilkS") (width 0.15) (fill solid))
    (fp_rect (start -1.4 -0.7) (end 1.4 0.7) (layer "F.CrtYd") (width 0.05) (fill none))
    (pad "1" smd rect (at -1.016 0.392) (size 0.2 0.475) (layers "F.Cu" "F.Paste" "F.Mask")
      (net 235 "/HDMI converter/HDMI_SDA") (pinfunction "CH1") (pintype "passive"))
    (pad "2" smd rect (at -0.517 0.392) (size 0.2 0.475) (layers "F.Cu" "F.Paste" "F.Mask")
      (net 232 "/HDMI converter/HDMI_SCL") (pinfunction "CH2") (pintype "passive"))
    (pad "3" smd rect (at -0.016 0.392) (size 0.2 0.475) (layers "F.Cu" "F.Paste" "F.Mask")
      (net 1 "GND") (pinfunction "GND") (pintype "passive"))
    (pad "4" smd rect (at 0.482 0.392) (size 0.2 0.475) (layers "F.Cu" "F.Paste" "F.Mask")
      (net 233 "/HDMI converter/HDMI_CEC") (pinfunction "CH3") (pintype "passive"))
    (pad "5" smd rect (at 0.982 0.392) (size 0.2 0.475) (layers "F.Cu" "F.Paste" "F.Mask")
      (net 234 "/HDMI converter/HDMI_DETECT") (pinfunction "CH4") (pintype "passive"))
    (pad "6" smd rect (at 0.982 -0.383 180) (size 0.2 0.475) (layers "F.Cu" "F.Paste" "F.Mask")
      (net 234 "/HDMI converter/HDMI_DETECT") (pinfunction "CH4") (pintype "passive"))
    (pad "7" smd rect (at 0.482 -0.383 180) (size 0.2 0.475) (layers "F.Cu" "F.Paste" "F.Mask")
      (net 233 "/HDMI converter/HDMI_CEC") (pinfunction "CH3") (pintype "passive"))
    (pad "8" smd rect (at -0.016 -0.383 180) (size 0.2 0.475) (layers "F.Cu" "F.Paste" "F.Mask")
      (net 1 "GND") (pinfunction "GND") (pintype "passive"))
    (pad "9" smd rect (at -0.517 -0.383 180) (size 0.2 0.475) (layers "F.Cu" "F.Paste" "F.Mask")
      (net 232 "/HDMI converter/HDMI_SCL") (pinfunction "CH2") (pintype "passive"))
    (pad "10" smd rect (at -1.016 -0.383 180) (size 0.2 0.475) (layers "F.Cu" "F.Paste" "F.Mask")
      (net 235 "/HDMI converter/HDMI_SDA") (pinfunction "CH1") (pintype "passive"))
  )
	(footprint "sa800u-baseboard-hw-footprints:R_0402_1005Metric" (layer "F.Cu")
    (tedit 5FD9C158)
    (at 138.2 133.05 -90)
    (descr "Resistor SMD 0402")
    (tags "resistor SMD 0402")
    (property "Author" "Antmicro")
    (property "License" "Apache-2.0")
    (property "MPN" "CR0402-FX-50R0GLF")
    (property "Manufacturer" "Bourns")
    (property "Sheetfile" "hdmi-converter.kicad_sch")
    (property "Sheetname" "HDMI converter")
    (property "Tolerance" "1%")
    (property "Val" "50R")
    (attr smd)
    (fp_text reference "R37" (at -4.611 15.55 -90) (layer "F.SilkS")
      (effects (font (size 0.7 0.7) (thickness 0.15)) (justify left bottom))
    )
    (fp_text value "R_50R_0402" (at 0 1.4 -90) (layer "F.Fab")
      (effects (font (size 0.7 0.7) (thickness 0.15)) (justify left bottom))
    )
    (fp_text user "${REFERENCE}" (at -0.95 3.168 -90) (layer "F.Fab") hide
      (effects (font (size 0.7 0.7) (thickness 0.15)) (justify left bottom))
    )
    (fp_text user "Author: Antmicro" (at -0.95 4.169 -90) (layer "F.Fab") hide
      (effects (font (size 0.7 0.7) (thickness 0.15)) (justify left bottom))
    )
    (fp_text user "License: Apache-2.0" (at -0.95 5.169 -90) (layer "F.Fab") hide
      (effects (font (size 0.7 0.7) (thickness 0.15)) (justify left bottom))
    )
    (fp_rect (start -0.93 -0.47) (end 0.93 0.47) (layer "F.CrtYd") (width 0.05) (fill none))
    (fp_rect (start -0.5 -0.25) (end 0.5 0.25) (layer "F.Fab") (width 0.15) (fill none))
    (pad "1" smd roundrect (at -0.485 0 270) (size 0.59 0.64) (layers "F.Cu" "F.Paste" "F.Mask") (roundrect_rratio 0.25)
      (net 187 "/HDMI converter/LT9611_VCC33_TX") (pintype "passive"))
    (pad "2" smd roundrect (at 0.485 0 270) (size 0.59 0.64) (layers "F.Cu" "F.Paste" "F.Mask") (roundrect_rratio 0.25)
      (net 205 "/HDMI converter/HDMI_TX_CLK_P") (pintype "passive"))
  )
	(footprint "sa800u-baseboard-hw-footprints:C_0402_1005Metric" (layer "F.Cu")
    (tedit 616D63CF)
    (at 136.75 134.95 -90)
    (descr "Capacitor SMD 0402")
    (tags "capacitor SMD 0402")
    (property "Author" "Antmicro")
    (property "Dielectric" "X5R")
    (property "License" "Apache-2.0")
    (property "MPN" "GRM155R61H104KE14D")
    (property "Manufacturer" "Murata")
    (property "Sheetfile" "hdmi-converter.kicad_sch")
    (property "Sheetname" "HDMI converter")
    (property "Val" "100n")
    (property "Voltage" "50V")
    (attr smd)
    (fp_text reference "C49" (at -4.61 15.46 -90) (layer "F.SilkS")
      (effects (font (size 0.7 0.7) (thickness 0.15)) (justify left bottom))
    )
    (fp_text value "C_100n_0402" (at 0 1.4 -90) (layer "F.Fab")
      (effects (font (size 0.7 0.7) (thickness 0.15)) (justify left bottom))
    )
    (fp_text user "License: Apache-2.0" (at -0.932 5.17 -90) (layer "F.Fab") hide
      (effects (font (size 0.7 0.7) (thickness 0.15)) (justify left bottom))
    )
    (fp_text user "${REFERENCE}" (at -0.932 3.168 -90) (layer "F.Fab") hide
      (effects (font (size 0.7 0.7) (thickness 0.15)) (justify left bottom))
    )
    (fp_text user "Author: Antmicro" (at -0.932 4.17 -90) (layer "F.Fab") hide
      (effects (font (size 0.7 0.7) (thickness 0.15)) (justify left bottom))
    )
    (fp_rect (start -0.94 -0.47) (end 0.94 0.47) (layer "F.CrtYd") (width 0.05) (fill none))
    (fp_rect (start -0.499 -0.249) (end 0.499 0.249) (layer "F.Fab") (width 0.15) (fill none))
    (pad "1" smd roundrect (at -0.484 0 270) (size 0.59 0.64) (layers "F.Cu" "F.Paste" "F.Mask") (roundrect_rratio 0.25)
      (net 207 "/HDMI converter/HDMI_TX_CLK_N") (pintype "passive"))
    (pad "2" smd roundrect (at 0.484 0 270) (size 0.59 0.64) (layers "F.Cu" "F.Paste" "F.Mask") (roundrect_rratio 0.25)
      (net 208 "/HDMI converter/HDMI_CLK_N") (pintype "passive"))
  )
)
